(kicad_pcb
	(version 20260206)
	(generator "pcbnew")
	(generator_version "10.0")
	(general
		(thickness 1.6)
		(legacy_teardrops no)
	)
	(paper "A4")
	(title_block
		(title "01162023_DA0F0TEBIF0_F0T_Expander_BD_F_brd_V02_OCP.brd")
		(comment 1 "Grand Teton / footprints 7899-7904 of 9728")
	)
	(layers
		(0 "F.Cu" signal "TOP")
		(4 "In1.Cu" signal "GND")
		(6 "In2.Cu" signal "VCC")
		(8 "In3.Cu" signal "VCC1")
		(10 "In4.Cu" signal "GND1")
		(12 "In5.Cu" signal "IN1")
		(14 "In6.Cu" signal "GND2")
		(16 "In7.Cu" signal "IN2")
		(18 "In8.Cu" signal "GND3")
		(20 "In9.Cu" signal "IN3")
		(22 "In10.Cu" signal "GND4")
		(24 "In11.Cu" signal "IN4")
		(26 "In12.Cu" signal "GND5")
		(28 "In13.Cu" signal "IN5")
		(30 "In14.Cu" signal "GND6")
		(32 "In15.Cu" signal "IN6")
		(34 "In16.Cu" signal "GND7")
		(2 "B.Cu" signal "BOTTOM")
		(9 "F.Adhes" user "F.Adhesive")
		(11 "B.Adhes" user "B.Adhesive")
		(13 "F.Paste" user "Package Geometry/Pastemask Top")
		(15 "B.Paste" user "Package Geometry/Pastemask Bottom")
		(5 "F.SilkS" user "Ref Des/Silkscreen Top")
		(7 "B.SilkS" user "Ref Des/Silkscreen Bottom")
		(1 "F.Mask" user "Board Geometry/Soldermask Top")
		(3 "B.Mask" user "Board Geometry/Soldermask Bottom")
		(17 "Dwgs.User" user "User.Drawings")
		(19 "Cmts.User" user "User.Comments")
		(21 "Eco1.User" user "User.Eco1")
		(23 "Eco2.User" user "User.Eco2")
		(25 "Edge.Cuts" user "Board Geometry/Outline")
		(27 "Margin" user)
		(31 "F.CrtYd" user "Package Geometry/Place Bound Top")
		(29 "B.CrtYd" user "Package Geometry/Place Bound Bottom")
		(35 "F.Fab" user "Ref Des/Assembly Top")
		(33 "B.Fab" user "Ref Des/Assembly Bottom")
	)
	(footprint ""
		(layer "B.Cu")
		(at 340.140798 -89.602818)
		(property "Reference" "C2679"
			(at 0 0 0)
			(layer "B.SilkS")
			(hide yes)
			(effects
				(font
					(size 1.27 1.27)
				)
				(justify mirror)
			)
		)
		(property "Value" ""
			(at 0 0 0)
			(layer "B.Fab")
			(effects
				(font
					(size 1.27 1.27)
				)
				(justify mirror)
			)
		)
		(duplicate_pad_numbers_are_jumpers no)
		(fp_line
			(start -0.7874 -0.4064)
			(end -0.7874 0.4064)
			(stroke
				(width 0.1524)
				(type default)
			)
			(layer "B.SilkS")
		)
		(fp_line
			(start -0.7874 0.4064)
			(end 0.7874 0.4064)
			(stroke
				(width 0.1524)
				(type default)
			)
			(layer "B.SilkS")
		)
		(fp_line
			(start 0.7874 -0.4064)
			(end -0.7874 -0.4064)
			(stroke
				(width 0.1524)
				(type default)
			)
			(layer "B.SilkS")
		)
		(fp_line
			(start 0.7874 0.4064)
			(end 0.7874 -0.4064)
			(stroke
				(width 0.1524)
				(type default)
			)
			(layer "B.SilkS")
		)
		(fp_line
			(start -0.67945 -0.3048)
			(end -0.67945 0.3048)
			(stroke
				(width 0.1)
				(type default)
			)
			(layer "B.Fab")
		)
		(fp_line
			(start -0.67945 0.3048)
			(end -0.120396 0.3048)
			(stroke
				(width 0.1)
				(type default)
			)
			(layer "B.Fab")
		)
		(fp_line
			(start -0.12065 -0.3048)
			(end -0.67945 -0.3048)
			(stroke
				(width 0.1)
				(type default)
			)
			(layer "B.Fab")
		)
		(fp_line
			(start -0.12065 -0.2794)
			(end -0.12065 -0.3048)
			(stroke
				(width 0.1)
				(type default)
			)
			(layer "B.Fab")
		)
		(fp_line
			(start -0.120396 0.2794)
			(end 0.12065 0.2794)
			(stroke
				(width 0.1)
				(type default)
			)
			(layer "B.Fab")
		)
		(fp_line
			(start -0.120396 0.3048)
			(end -0.120396 0.2794)
			(stroke
				(width 0.1)
				(type default)
			)
			(layer "B.Fab")
		)
		(fp_line
			(start 0.12065 -0.305054)
			(end 0.12065 -0.2794)
			(stroke
				(width 0.1)
				(type default)
			)
			(layer "B.Fab")
		)
		(fp_line
			(start 0.12065 -0.2794)
			(end -0.12065 -0.2794)
			(stroke
				(width 0.1)
				(type default)
			)
			(layer "B.Fab")
		)
		(fp_line
			(start 0.12065 0.2794)
			(end 0.12065 0.3048)
			(stroke
				(width 0.1)
				(type default)
			)
			(layer "B.Fab")
		)
		(fp_line
			(start 0.12065 0.3048)
			(end 0.67945 0.3048)
			(stroke
				(width 0.1)
				(type default)
			)
			(layer "B.Fab")
		)
		(fp_line
			(start 0.67945 -0.305054)
			(end 0.12065 -0.305054)
			(stroke
				(width 0.1)
				(type default)
			)
			(layer "B.Fab")
		)
		(fp_line
			(start 0.67945 0.3048)
			(end 0.67945 -0.305054)
			(stroke
				(width 0.1)
				(type default)
			)
			(layer "B.Fab")
		)
		(pad "1" smd circle
			(at 0.40005 0 180)
			(size 0 0)
			(layers "B.Cu" "B.Mask" "B.Paste")
			(net "P3V3_VDD_9ZXL0851_8_15")
		)
		(pad "2" smd circle
			(at -0.40005 0 180)
			(size 0 0)
			(layers "B.Cu" "B.Mask" "B.Paste")
			(net "GND")
		)
	)
	(footprint ""
		(layer "B.Cu")
		(at 341.111586 -283.818584 90)
		(property "Reference" "PR148"
			(at 0 0 90)
			(layer "B.SilkS")
			(hide yes)
			(effects
				(font
					(size 1.27 1.27)
				)
				(justify mirror)
			)
		)
		(property "Value" ""
			(at 0 0 90)
			(layer "B.Fab")
			(effects
				(font
					(size 1.27 1.27)
				)
				(justify mirror)
			)
		)
		(duplicate_pad_numbers_are_jumpers no)
		(fp_line
			(start 0.7874 -0.4064)
			(end -0.7874 -0.4064)
			(stroke
				(width 0.1524)
				(type default)
			)
			(layer "B.SilkS")
		)
		(fp_line
			(start -0.7874 -0.4064)
			(end -0.7874 0.4064)
			(stroke
				(width 0.1524)
				(type default)
			)
			(layer "B.SilkS")
		)
		(fp_line
			(start 0.7874 0.4064)
			(end 0.7874 -0.4064)
			(stroke
				(width 0.1524)
				(type default)
			)
			(layer "B.SilkS")
		)
		(fp_line
			(start -0.7874 0.4064)
			(end 0.7874 0.4064)
			(stroke
				(width 0.1524)
				(type default)
			)
			(layer "B.SilkS")
		)
		(fp_line
			(start 0.67945 -0.305054)
			(end 0.12065 -0.305054)
			(stroke
				(width 0.1)
				(type default)
			)
			(layer "B.Fab")
		)
		(fp_line
			(start 0.12065 -0.305054)
			(end 0.12065 -0.2794)
			(stroke
				(width 0.1)
				(type default)
			)
			(layer "B.Fab")
		)
		(fp_line
			(start -0.12065 -0.3048)
			(end -0.67945 -0.3048)
			(stroke
				(width 0.1)
				(type default)
			)
			(layer "B.Fab")
		)
		(fp_line
			(start -0.67945 -0.3048)
			(end -0.67945 0.3048)
			(stroke
				(width 0.1)
				(type default)
			)
			(layer "B.Fab")
		)
		(fp_line
			(start 0.12065 -0.2794)
			(end -0.12065 -0.2794)
			(stroke
				(width 0.1)
				(type default)
			)
			(layer "B.Fab")
		)
		(fp_line
			(start -0.12065 -0.2794)
			(end -0.12065 -0.3048)
			(stroke
				(width 0.1)
				(type default)
			)
			(layer "B.Fab")
		)
		(fp_line
			(start 0.12065 0.2794)
			(end 0.12065 0.3048)
			(stroke
				(width 0.1)
				(type default)
			)
			(layer "B.Fab")
		)
		(fp_line
			(start -0.120396 0.2794)
			(end 0.12065 0.2794)
			(stroke
				(width 0.1)
				(type default)
			)
			(layer "B.Fab")
		)
		(fp_line
			(start 0.67945 0.3048)
			(end 0.67945 -0.305054)
			(stroke
				(width 0.1)
				(type default)
			)
			(layer "B.Fab")
		)
		(fp_line
			(start 0.12065 0.3048)
			(end 0.67945 0.3048)
			(stroke
				(width 0.1)
				(type default)
			)
			(layer "B.Fab")
		)
		(fp_line
			(start -0.120396 0.3048)
			(end -0.120396 0.2794)
			(stroke
				(width 0.1)
				(type default)
			)
			(layer "B.Fab")
		)
		(fp_line
			(start -0.67945 0.3048)
			(end -0.120396 0.3048)
			(stroke
				(width 0.1)
				(type default)
			)
			(layer "B.Fab")
		)
		(pad "1" smd circle
			(at 0.40005 0 270)
			(size 0 0)
			(layers "B.Cu" "B.Mask" "B.Paste")
			(net "P0V8_PEX2_PVCC")
		)
		(pad "2" smd circle
			(at -0.40005 0 270)
			(size 0 0)
			(layers "B.Cu" "B.Mask" "B.Paste")
			(net "P0V8_PEX2_VCC1")
		)
	)
	(footprint ""
		(layer "B.Cu")
		(at 222.27413 -200.984104 90)
		(property "Reference" "R460"
			(at 0 0 90)
			(layer "B.SilkS")
			(hide yes)
			(effects
				(font
					(size 1.27 1.27)
				)
				(justify mirror)
			)
		)
		(property "Value" ""
			(at 0 0 90)
			(layer "B.Fab")
			(effects
				(font
					(size 1.27 1.27)
				)
				(justify mirror)
			)
		)
		(duplicate_pad_numbers_are_jumpers no)
		(fp_line
			(start 0.7874 -0.4064)
			(end -0.7874 -0.4064)
			(stroke
				(width 0.1524)
				(type default)
			)
			(layer "B.SilkS")
		)
		(fp_line
			(start -0.7874 -0.4064)
			(end -0.7874 0.4064)
			(stroke
				(width 0.1524)
				(type default)
			)
			(layer "B.SilkS")
		)
		(fp_line
			(start 0.7874 0.4064)
			(end 0.7874 -0.4064)
			(stroke
				(width 0.1524)
				(type default)
			)
			(layer "B.SilkS")
		)
		(fp_line
			(start -0.7874 0.4064)
			(end 0.7874 0.4064)
			(stroke
				(width 0.1524)
				(type default)
			)
			(layer "B.SilkS")
		)
		(fp_line
			(start 0.67945 -0.305054)
			(end 0.12065 -0.305054)
			(stroke
				(width 0.1)
				(type default)
			)
			(layer "B.Fab")
		)
		(fp_line
			(start 0.12065 -0.305054)
			(end 0.12065 -0.2794)
			(stroke
				(width 0.1)
				(type default)
			)
			(layer "B.Fab")
		)
		(fp_line
			(start -0.12065 -0.3048)
			(end -0.67945 -0.3048)
			(stroke
				(width 0.1)
				(type default)
			)
			(layer "B.Fab")
		)
		(fp_line
			(start -0.67945 -0.3048)
			(end -0.67945 0.3048)
			(stroke
				(width 0.1)
				(type default)
			)
			(layer "B.Fab")
		)
		(fp_line
			(start 0.12065 -0.2794)
			(end -0.12065 -0.2794)
			(stroke
				(width 0.1)
				(type default)
			)
			(layer "B.Fab")
		)
		(fp_line
			(start -0.12065 -0.2794)
			(end -0.12065 -0.3048)
			(stroke
				(width 0.1)
				(type default)
			)
			(layer "B.Fab")
		)
		(fp_line
			(start 0.12065 0.2794)
			(end 0.12065 0.3048)
			(stroke
				(width 0.1)
				(type default)
			)
			(layer "B.Fab")
		)
		(fp_line
			(start -0.120396 0.2794)
			(end 0.12065 0.2794)
			(stroke
				(width 0.1)
				(type default)
			)
			(layer "B.Fab")
		)
		(fp_line
			(start 0.67945 0.3048)
			(end 0.67945 -0.305054)
			(stroke
				(width 0.1)
				(type default)
			)
			(layer "B.Fab")
		)
		(fp_line
			(start 0.12065 0.3048)
			(end 0.67945 0.3048)
			(stroke
				(width 0.1)
				(type default)
			)
			(layer "B.Fab")
		)
		(fp_line
			(start -0.120396 0.3048)
			(end -0.120396 0.2794)
			(stroke
				(width 0.1)
				(type default)
			)
			(layer "B.Fab")
		)
		(fp_line
			(start -0.67945 0.3048)
			(end -0.120396 0.3048)
			(stroke
				(width 0.1)
				(type default)
			)
			(layer "B.Fab")
		)
		(pad "1" smd circle
			(at 0.40005 0 270)
			(size 0 0)
			(layers "B.Cu" "B.Mask" "B.Paste")
			(net "SPI_BIC1_MOSI")
		)
		(pad "2" smd circle
			(at -0.40005 0 270)
			(size 0 0)
			(layers "B.Cu" "B.Mask" "B.Paste")
			(net "SPI_BIC1_MOSI_R")
		)
	)
	(footprint ""
		(layer "B.Cu")
		(at 413.649922 -288.299906 90)
		(property "Reference" "C3444"
			(at 0 0 90)
			(layer "B.SilkS")
			(hide yes)
			(effects
				(font
					(size 1.27 1.27)
				)
				(justify mirror)
			)
		)
		(property "Value" ""
			(at 0 0 90)
			(layer "B.Fab")
			(effects
				(font
					(size 1.27 1.27)
				)
				(justify mirror)
			)
		)
		(duplicate_pad_numbers_are_jumpers no)
		(fp_line
			(start 0.299974 -0.150114)
			(end -0.299974 -0.150114)
			(stroke
				(width 0.1)
				(type default)
			)
			(layer "B.Fab")
		)
		(fp_line
			(start -0.299974 -0.150114)
			(end -0.299974 0.150114)
			(stroke
				(width 0.1)
				(type default)
			)
			(layer "B.Fab")
		)
		(fp_line
			(start 0.299974 0.150114)
			(end 0.299974 -0.150114)
			(stroke
				(width 0.1)
				(type default)
			)
			(layer "B.Fab")
		)
		(fp_line
			(start -0.299974 0.150114)
			(end 0.299974 0.150114)
			(stroke
				(width 0.1)
				(type default)
			)
			(layer "B.Fab")
		)
		(pad "1" smd rect
			(at 0.2667 0 270)
			(size 0.3048 0.381)
			(layers "B.Cu" "B.Mask" "B.Paste")
			(net "P1V25_PEX3")
		)
		(pad "2" smd rect
			(at -0.2667 0 270)
			(size 0.3048 0.381)
			(layers "B.Cu" "B.Mask" "B.Paste")
			(net "GND")
		)
	)
	(footprint ""
		(layer "B.Cu")
		(at 99.055428 -377.387612)
		(property "Reference" "R1831"
			(at 0 0 0)
			(layer "B.SilkS")
			(hide yes)
			(effects
				(font
					(size 1.27 1.27)
				)
				(justify mirror)
			)
		)
		(property "Value" ""
			(at 0 0 0)
			(layer "B.Fab")
			(effects
				(font
					(size 1.27 1.27)
				)
				(justify mirror)
			)
		)
		(duplicate_pad_numbers_are_jumpers no)
		(fp_line
			(start -0.7874 -0.4064)
			(end -0.7874 0.4064)
			(stroke
				(width 0.1524)
				(type default)
			)
			(layer "B.SilkS")
		)
		(fp_line
			(start -0.7874 0.4064)
			(end 0.7874 0.4064)
			(stroke
				(width 0.1524)
				(type default)
			)
			(layer "B.SilkS")
		)
		(fp_line
			(start 0.7874 -0.4064)
			(end -0.7874 -0.4064)
			(stroke
				(width 0.1524)
				(type default)
			)
			(layer "B.SilkS")
		)
		(fp_line
			(start 0.7874 0.4064)
			(end 0.7874 -0.4064)
			(stroke
				(width 0.1524)
				(type default)
			)
			(layer "B.SilkS")
		)
		(fp_line
			(start -0.67945 -0.3048)
			(end -0.67945 0.3048)
			(stroke
				(width 0.1)
				(type default)
			)
			(layer "B.Fab")
		)
		(fp_line
			(start -0.67945 0.3048)
			(end -0.120396 0.3048)
			(stroke
				(width 0.1)
				(type default)
			)
			(layer "B.Fab")
		)
		(fp_line
			(start -0.12065 -0.3048)
			(end -0.67945 -0.3048)
			(stroke
				(width 0.1)
				(type default)
			)
			(layer "B.Fab")
		)
		(fp_line
			(start -0.12065 -0.2794)
			(end -0.12065 -0.3048)
			(stroke
				(width 0.1)
				(type default)
			)
			(layer "B.Fab")
		)
		(fp_line
			(start -0.120396 0.2794)
			(end 0.12065 0.2794)
			(stroke
				(width 0.1)
				(type default)
			)
			(layer "B.Fab")
		)
		(fp_line
			(start -0.120396 0.3048)
			(end -0.120396 0.2794)
			(stroke
				(width 0.1)
				(type default)
			)
			(layer "B.Fab")
		)
		(fp_line
			(start 0.12065 -0.305054)
			(end 0.12065 -0.2794)
			(stroke
				(width 0.1)
				(type default)
			)
			(layer "B.Fab")
		)
		(fp_line
			(start 0.12065 -0.2794)
			(end -0.12065 -0.2794)
			(stroke
				(width 0.1)
				(type default)
			)
			(layer "B.Fab")
		)
		(fp_line
			(start 0.12065 0.2794)
			(end 0.12065 0.3048)
			(stroke
				(width 0.1)
				(type default)
			)
			(layer "B.Fab")
		)
		(fp_line
			(start 0.12065 0.3048)
			(end 0.67945 0.3048)
			(stroke
				(width 0.1)
				(type default)
			)
			(layer "B.Fab")
		)
		(fp_line
			(start 0.67945 -0.305054)
			(end 0.12065 -0.305054)
			(stroke
				(width 0.1)
				(type default)
			)
			(layer "B.Fab")
		)
		(fp_line
			(start 0.67945 0.3048)
			(end 0.67945 -0.305054)
			(stroke
				(width 0.1)
				(type default)
			)
			(layer "B.Fab")
		)
		(pad "1" smd circle
			(at 0.40005 0 180)
			(size 0 0)
			(layers "B.Cu" "B.Mask" "B.Paste")
			(net "SMB_GPU_2_R_SCL")
		)
		(pad "2" smd circle
			(at -0.40005 0 180)
			(size 0 0)
			(layers "B.Cu" "B.Mask" "B.Paste")
			(net "SMB_GPU_2_SCL")
		)
	)
	(footprint ""
		(layer "B.Cu")
		(at 3.065272 -274.646644)
		(property "Reference" "C4233"
			(at 0 0 0)
			(layer "B.SilkS")
			(hide yes)
			(effects
				(font
					(size 1.27 1.27)
				)
				(justify mirror)
			)
		)
		(property "Value" ""
			(at 0 0 0)
			(layer "B.Fab")
			(effects
				(font
					(size 1.27 1.27)
				)
				(justify mirror)
			)
		)
		(duplicate_pad_numbers_are_jumpers no)
		(fp_line
			(start -1.2954 -0.5842)
			(end -1.2954 0.5842)
			(stroke
				(width 0.1524)
				(type default)
			)
			(layer "B.SilkS")
		)
		(fp_line
			(start -1.2954 0.5842)
			(end 1.2954 0.5842)
			(stroke
				(width 0.1524)
				(type default)
			)
			(layer "B.SilkS")
		)
		(fp_line
			(start 1.2954 -0.5842)
			(end -1.2954 -0.5842)
			(stroke
				(width 0.1524)
				(type default)
			)
			(layer "B.SilkS")
		)
		(fp_line
			(start 1.2954 0.5842)
			(end 1.2954 -0.5842)
			(stroke
				(width 0.1524)
				(type default)
			)
			(layer "B.SilkS")
		)
		(fp_line
			(start -1.1938 -0.4064)
			(end -1.1938 0.4064)
			(stroke
				(width 0.1)
				(type default)
			)
			(layer "B.Fab")
		)
		(fp_line
			(start -1.1938 0.4064)
			(end -0.8636 0.4064)
			(stroke
				(width 0.1)
				(type default)
			)
			(layer "B.Fab")
		)
		(fp_line
			(start -0.8636 -0.4572)
			(end -0.8636 -0.4064)
			(stroke
				(width 0.1)
				(type default)
			)
			(layer "B.Fab")
		)
		(fp_line
			(start -0.8636 -0.4064)
			(end -1.1938 -0.4064)
			(stroke
				(width 0.1)
				(type default)
			)
			(layer "B.Fab")
		)
		(fp_line
			(start -0.8636 0.4064)
			(end -0.8636 0.4572)
			(stroke
				(width 0.1)
				(type default)
			)
			(layer "B.Fab")
		)
		(fp_line
			(start -0.8636 0.4572)
			(end 0.8636 0.4572)
			(stroke
				(width 0.1)
				(type default)
			)
			(layer "B.Fab")
		)
		(fp_line
			(start 0.8636 -0.4572)
			(end -0.8636 -0.4572)
			(stroke
				(width 0.1)
				(type default)
			)
			(layer "B.Fab")
		)
		(fp_line
			(start 0.8636 -0.4064)
			(end 0.8636 -0.4572)
			(stroke
				(width 0.1)
				(type default)
			)
			(layer "B.Fab")
		)
		(fp_line
			(start 0.8636 0.4064)
			(end 1.1938 0.4064)
			(stroke
				(width 0.1)
				(type default)
			)
			(layer "B.Fab")
		)
		(fp_line
			(start 0.8636 0.4572)
			(end 0.8636 0.4064)
			(stroke
				(width 0.1)
				(type default)
			)
			(layer "B.Fab")
		)
		(fp_line
			(start 1.1938 -0.4064)
			(end 0.8636 -0.4064)
			(stroke
				(width 0.1)
				(type default)
			)
			(layer "B.Fab")
		)
		(fp_line
			(start 1.1938 0.4064)
			(end 1.1938 -0.4064)
			(stroke
				(width 0.1)
				(type default)
			)
			(layer "B.Fab")
		)
		(pad "1" smd rect
			(at 0.7366 0 270)
			(size 0.7112 0.8128)
			(layers "B.Cu" "B.Mask" "B.Paste")
			(net "P1V25_PEX0")
		)
		(pad "2" smd rect
			(at -0.7366 0 270)
			(size 0.7112 0.8128)
			(layers "B.Cu" "B.Mask" "B.Paste")
			(net "GND")
		)
	)
)
